(kicad_pcb
	(version 20260206)
	(generator "pcbnew")
	(generator_version "10.0")
	(general
		(thickness 1.6)
		(legacy_teardrops no)
	)
	(paper "A4")
	(title_block
		(title "peb — Lightning_PEB_BRD.brd")
		(comment 1 "Lightning (Wiwynn / Facebook NVMe JBOF) / footprints 1521-1527 of 2563")
	)
	(layers
		(0 "F.Cu" signal "TOP")
		(4 "In1.Cu" signal "L2GND")
		(6 "In2.Cu" signal "L3")
		(8 "In3.Cu" signal "L4VCC")
		(10 "In4.Cu" signal "L5VCC")
		(12 "In5.Cu" signal "L6")
		(14 "In6.Cu" signal "L7GND")
		(2 "B.Cu" signal "BOTTOM")
		(9 "F.Adhes" user "F.Adhesive")
		(11 "B.Adhes" user "B.Adhesive")
		(13 "F.Paste" user "Package Geometry/Pastemask Top")
		(15 "B.Paste" user "Package Geometry/Pastemask Bottom")
		(5 "F.SilkS" user "Ref Des/Silkscreen Top")
		(7 "B.SilkS" user "Ref Des/Silkscreen Bottom")
		(1 "F.Mask" user "Board Geometry/Soldermask Top")
		(3 "B.Mask" user "Board Geometry/Soldermask Bottom")
		(17 "Dwgs.User" user "User.Drawings")
		(19 "Cmts.User" user "User.Comments")
		(21 "Eco1.User" user "User.Eco1")
		(23 "Eco2.User" user "User.Eco2")
		(25 "Edge.Cuts" user "Board Geometry/Outline")
		(27 "Margin" user)
		(31 "F.CrtYd" user "Package Geometry/Place Bound Top")
		(29 "B.CrtYd" user "Package Geometry/Place Bound Bottom")
		(35 "F.Fab" user "Ref Des/Assembly Top")
		(33 "B.Fab" user "Ref Des/Assembly Bottom")
	)
	(footprint ""
		(layer "F.Cu")
		(at 218.797124 -203.047092)
		(property "Reference" "R7919"
			(at 0 0 0)
			(layer "F.SilkS")
			(hide yes)
			(effects
				(font
					(size 1.27 1.27)
				)
			)
		)
		(property "Value" "0R2J-2-GP"
			(at 0.064008 -3.993896 0)
			(unlocked yes)
			(layer "F.Fab")
			(hide yes)
			(effects
				(font
					(size 1.016 1.016)
					(thickness 0.1524)
				)
			)
		)
		(property "Device Type" "R402H16"
			(at 0.064008 -5.517896 0)
			(unlocked yes)
			(layer "F.Fab")
			(hide yes)
			(effects
				(font
					(size 1.016 1.016)
					(thickness 0.1524)
				)
			)
		)
		(duplicate_pad_numbers_are_jumpers no)
		(fp_line
			(start -0.508 -0.9398)
			(end -0.508 0.9398)
			(stroke
				(width 0.1524)
				(type default)
			)
			(layer "F.SilkS")
		)
		(fp_line
			(start 0.508 -0.9398)
			(end -0.508 -0.9398)
			(stroke
				(width 0.1524)
				(type default)
			)
			(layer "F.SilkS")
		)
		(fp_rect
			(start -0.508 0.9398)
			(end 0.508 -0.9398)
			(stroke
				(width 0)
				(type default)
			)
			(fill no)
			(layer "F.CrtYd")
		)
		(fp_rect
			(start -0.508 0.9398)
			(end 0.508 -0.9398)
			(stroke
				(width 0)
				(type default)
			)
			(fill no)
			(layer "F.Fab")
		)
		(pad "1" smd custom
			(at 0 -0.4445)
			(size 0.1397 0.1397)
			(layers "F.Cu" "F.Mask" "F.Paste")
			(net "TWI_SCL1")
			(options
				(clearance outline)
				(anchor circle)
			)
			(primitives
				(gr_poly
					(pts
						(arc
							(start -0.1778 -0.2794)
							(mid -0.249642 -0.249642)
							(end -0.2794 -0.1778)
						)
						(arc
							(start -0.2794 0.1778)
							(mid -0.249642 0.249642)
							(end -0.1778 0.2794)
						)
						(arc
							(start 0.1778 0.2794)
							(mid 0.249642 0.249642)
							(end 0.2794 0.1778)
						)
						(arc
							(start 0.2794 -0.1778)
							(mid 0.249642 -0.249642)
							(end 0.1778 -0.2794)
						)
					)
					(width 0)
					(fill yes)
				)
			)
		)
		(pad "2" smd custom
			(at 0 0.4445)
			(size 0.1397 0.1397)
			(layers "F.Cu" "F.Mask" "F.Paste")
			(net "I2C_GPIO_SCL_3")
			(options
				(clearance outline)
				(anchor circle)
			)
			(primitives
				(gr_poly
					(pts
						(arc
							(start -0.1778 -0.2794)
							(mid -0.249642 -0.249642)
							(end -0.2794 -0.1778)
						)
						(arc
							(start -0.2794 0.1778)
							(mid -0.249642 0.249642)
							(end -0.1778 0.2794)
						)
						(arc
							(start 0.1778 0.2794)
							(mid 0.249642 0.249642)
							(end 0.2794 0.1778)
						)
						(arc
							(start 0.2794 -0.1778)
							(mid 0.249642 -0.249642)
							(end 0.1778 -0.2794)
						)
					)
					(width 0)
					(fill yes)
				)
			)
		)
	)
	(footprint ""
		(layer "F.Cu")
		(at 21.0312 -187.0456 90)
		(property "Reference" "PC1083"
			(at 0 0 90)
			(layer "F.SilkS")
			(hide yes)
			(effects
				(font
					(size 1.27 1.27)
				)
			)
		)
		(property "Value" "SC1U25V3KX-GP"
			(at 0 -2.8194 90)
			(unlocked yes)
			(layer "F.Fab")
			(hide yes)
			(effects
				(font
					(size 1.016 1.016)
					(thickness 0.1524)
				)
			)
		)
		(property "Device Type" "C603H36"
			(at 0 -4.3434 90)
			(unlocked yes)
			(layer "F.Fab")
			(hide yes)
			(effects
				(font
					(size 1.016 1.016)
					(thickness 0.1524)
				)
			)
		)
		(duplicate_pad_numbers_are_jumpers no)
		(fp_line
			(start 0.508 0)
			(end -0.508 0)
			(stroke
				(width 0.2032)
				(type default)
			)
			(layer "F.SilkS")
		)
		(fp_rect
			(start -0.5842 1.3335)
			(end 0.5842 -1.3335)
			(stroke
				(width 0)
				(type default)
			)
			(fill no)
			(layer "F.CrtYd")
		)
		(fp_rect
			(start -0.5842 1.3335)
			(end 0.5842 -1.3335)
			(stroke
				(width 0)
				(type default)
			)
			(fill no)
			(layer "F.Fab")
		)
		(pad "1" smd custom
			(at 0 -0.762 90)
			(size 0.2159 0.2159)
			(layers "F.Cu" "F.Mask" "F.Paste")
			(net "MB0_VCC")
			(options
				(clearance outline)
				(anchor circle)
			)
			(primitives
				(gr_poly
					(pts
						(arc
							(start -0.3302 -0.4318)
							(mid -0.402042 -0.402042)
							(end -0.4318 -0.3302)
						)
						(arc
							(start -0.4318 0.3302)
							(mid -0.402042 0.402042)
							(end -0.3302 0.4318)
						)
						(arc
							(start 0.3302 0.4318)
							(mid 0.402042 0.402042)
							(end 0.4318 0.3302)
						)
						(arc
							(start 0.4318 -0.3302)
							(mid 0.402042 -0.402042)
							(end 0.3302 -0.4318)
						)
					)
					(width 0)
					(fill yes)
				)
			)
		)
		(pad "2" smd custom
			(at 0 0.762 90)
			(size 0.2159 0.2159)
			(layers "F.Cu" "F.Mask" "F.Paste")
			(net "AGND_CURRENT_MON")
			(options
				(clearance outline)
				(anchor circle)
			)
			(primitives
				(gr_poly
					(pts
						(arc
							(start -0.3302 -0.4318)
							(mid -0.402042 -0.402042)
							(end -0.4318 -0.3302)
						)
						(arc
							(start -0.4318 0.3302)
							(mid -0.402042 0.402042)
							(end -0.3302 0.4318)
						)
						(arc
							(start 0.3302 0.4318)
							(mid 0.402042 0.402042)
							(end 0.4318 0.3302)
						)
						(arc
							(start 0.4318 -0.3302)
							(mid 0.402042 -0.402042)
							(end 0.3302 -0.4318)
						)
					)
					(width 0)
					(fill yes)
				)
			)
		)
	)
	(footprint ""
		(layer "F.Cu")
		(at 158.334202 -58.447432)
		(property "Reference" "PR178"
			(at 0 0 0)
			(layer "F.SilkS")
			(hide yes)
			(effects
				(font
					(size 1.27 1.27)
				)
			)
		)
		(property "Value" "51KR2F-L-GP"
			(at 0.064008 -3.993896 0)
			(unlocked yes)
			(layer "F.Fab")
			(hide yes)
			(effects
				(font
					(size 1.016 1.016)
					(thickness 0.1524)
				)
			)
		)
		(property "Device Type" "R402H16"
			(at 0.064008 -5.517896 0)
			(unlocked yes)
			(layer "F.Fab")
			(hide yes)
			(effects
				(font
					(size 1.016 1.016)
					(thickness 0.1524)
				)
			)
		)
		(duplicate_pad_numbers_are_jumpers no)
		(fp_line
			(start -0.508 -0.9398)
			(end -0.508 0.9398)
			(stroke
				(width 0.1524)
				(type default)
			)
			(layer "F.SilkS")
		)
		(fp_line
			(start 0.508 -0.9398)
			(end -0.508 -0.9398)
			(stroke
				(width 0.1524)
				(type default)
			)
			(layer "F.SilkS")
		)
		(fp_rect
			(start -0.508 0.9398)
			(end 0.508 -0.9398)
			(stroke
				(width 0)
				(type default)
			)
			(fill no)
			(layer "F.CrtYd")
		)
		(fp_rect
			(start -0.508 0.9398)
			(end 0.508 -0.9398)
			(stroke
				(width 0)
				(type default)
			)
			(fill no)
			(layer "F.Fab")
		)
		(pad "1" smd custom
			(at 0 -0.4445)
			(size 0.1397 0.1397)
			(layers "F.Cu" "F.Mask" "F.Paste")
			(net "P0V9_EN")
			(options
				(clearance outline)
				(anchor circle)
			)
			(primitives
				(gr_poly
					(pts
						(arc
							(start -0.1778 -0.2794)
							(mid -0.249642 -0.249642)
							(end -0.2794 -0.1778)
						)
						(arc
							(start -0.2794 0.1778)
							(mid -0.249642 0.249642)
							(end -0.1778 0.2794)
						)
						(arc
							(start 0.1778 0.2794)
							(mid 0.249642 0.249642)
							(end 0.2794 0.1778)
						)
						(arc
							(start 0.2794 -0.1778)
							(mid 0.249642 -0.249642)
							(end 0.1778 -0.2794)
						)
					)
					(width 0)
					(fill yes)
				)
			)
		)
		(pad "2" smd custom
			(at 0 0.4445)
			(size 0.1397 0.1397)
			(layers "F.Cu" "F.Mask" "F.Paste")
			(net "GND")
			(options
				(clearance outline)
				(anchor circle)
			)
			(primitives
				(gr_poly
					(pts
						(arc
							(start -0.1778 -0.2794)
							(mid -0.249642 -0.249642)
							(end -0.2794 -0.1778)
						)
						(arc
							(start -0.2794 0.1778)
							(mid -0.249642 0.249642)
							(end -0.1778 0.2794)
						)
						(arc
							(start 0.1778 0.2794)
							(mid 0.249642 0.249642)
							(end 0.2794 0.1778)
						)
						(arc
							(start 0.2794 -0.1778)
							(mid 0.249642 -0.249642)
							(end 0.1778 -0.2794)
						)
					)
					(width 0)
					(fill yes)
				)
			)
		)
	)
	(footprint ""
		(layer "F.Cu")
		(at 123.928124 -196.443092 180)
		(property "Reference" "R548"
			(at 0 0 180)
			(layer "F.SilkS")
			(hide yes)
			(effects
				(font
					(size 1.27 1.27)
				)
			)
		)
		(property "Value" "10KR2F-2-GP"
			(at 0.064008 -3.993896 180)
			(unlocked yes)
			(layer "F.Fab")
			(hide yes)
			(effects
				(font
					(size 1.016 1.016)
					(thickness 0.1524)
				)
			)
		)
		(property "Device Type" "R402H16"
			(at 0.064008 -5.517896 180)
			(unlocked yes)
			(layer "F.Fab")
			(hide yes)
			(effects
				(font
					(size 1.016 1.016)
					(thickness 0.1524)
				)
			)
		)
		(duplicate_pad_numbers_are_jumpers no)
		(fp_line
			(start 0.508 -0.9398)
			(end -0.508 -0.9398)
			(stroke
				(width 0.1524)
				(type default)
			)
			(layer "F.SilkS")
		)
		(fp_line
			(start -0.508 -0.9398)
			(end -0.508 0.9398)
			(stroke
				(width 0.1524)
				(type default)
			)
			(layer "F.SilkS")
		)
		(fp_rect
			(start -0.508 0.9398)
			(end 0.508 -0.9398)
			(stroke
				(width 0)
				(type default)
			)
			(fill no)
			(layer "F.CrtYd")
		)
		(fp_rect
			(start -0.508 0.9398)
			(end 0.508 -0.9398)
			(stroke
				(width 0)
				(type default)
			)
			(fill no)
			(layer "F.Fab")
		)
		(pad "1" smd custom
			(at 0 -0.4445 180)
			(size 0.1397 0.1397)
			(layers "F.Cu" "F.Mask" "F.Paste")
			(net "GND")
			(options
				(clearance outline)
				(anchor circle)
			)
			(primitives
				(gr_poly
					(pts
						(arc
							(start -0.1778 -0.2794)
							(mid -0.249642 -0.249642)
							(end -0.2794 -0.1778)
						)
						(arc
							(start -0.2794 0.1778)
							(mid -0.249642 0.249642)
							(end -0.1778 0.2794)
						)
						(arc
							(start 0.1778 0.2794)
							(mid 0.249642 0.249642)
							(end 0.2794 0.1778)
						)
						(arc
							(start 0.2794 -0.1778)
							(mid 0.249642 -0.249642)
							(end 0.1778 -0.2794)
						)
					)
					(width 0)
					(fill yes)
				)
			)
		)
		(pad "2" smd custom
			(at 0 0.4445 180)
			(size 0.1397 0.1397)
			(layers "F.Cu" "F.Mask" "F.Paste")
			(net "IOEXP2_AD1")
			(options
				(clearance outline)
				(anchor circle)
			)
			(primitives
				(gr_poly
					(pts
						(arc
							(start -0.1778 -0.2794)
							(mid -0.249642 -0.249642)
							(end -0.2794 -0.1778)
						)
						(arc
							(start -0.2794 0.1778)
							(mid -0.249642 0.249642)
							(end -0.1778 0.2794)
						)
						(arc
							(start 0.1778 0.2794)
							(mid 0.249642 0.249642)
							(end 0.2794 0.1778)
						)
						(arc
							(start 0.2794 -0.1778)
							(mid 0.249642 -0.249642)
							(end 0.1778 -0.2794)
						)
					)
					(width 0)
					(fill yes)
				)
			)
		)
	)
	(footprint ""
		(layer "F.Cu")
		(at 51.181 -195.58 90)
		(property "Reference" "U31"
			(at 0 0 90)
			(layer "F.SilkS")
			(hide yes)
			(effects
				(font
					(size 1.27 1.27)
				)
			)
		)
		(property "Value" "PCA9511ADP-T-GP"
			(at 0 -13.1572 90)
			(unlocked yes)
			(layer "F.Fab")
			(hide yes)
			(effects
				(font
					(size 1.016 1.016)
					(thickness 0.1524)
				)
			)
		)
		(property "Device Type" "SSOIC8-2H44"
			(at 0 -15.1892 90)
			(unlocked yes)
			(layer "F.Fab")
			(hide yes)
			(effects
				(font
					(size 1.016 1.016)
					(thickness 0.1524)
				)
			)
		)
		(duplicate_pad_numbers_are_jumpers no)
		(fp_line
			(start 1.0922 -1.016)
			(end 1.0922 1.016)
			(stroke
				(width 0.1524)
				(type default)
			)
			(layer "F.SilkS")
		)
		(fp_line
			(start -1.9304 -1.016)
			(end 1.0922 -1.016)
			(stroke
				(width 0.1524)
				(type default)
			)
			(layer "F.SilkS")
		)
		(fp_line
			(start -1.524 0)
			(end -1.9304 -0.4064)
			(stroke
				(width 0.1524)
				(type default)
			)
			(layer "F.SilkS")
		)
		(fp_line
			(start -1.524 0)
			(end -1.9304 0.4064)
			(stroke
				(width 0.1524)
				(type default)
			)
			(layer "F.SilkS")
		)
		(fp_line
			(start 1.0922 1.016)
			(end -1.9304 1.016)
			(stroke
				(width 0.1524)
				(type default)
			)
			(layer "F.SilkS")
		)
		(fp_line
			(start -1.9304 1.016)
			(end -1.9304 -1.016)
			(stroke
				(width 0.1524)
				(type default)
			)
			(layer "F.SilkS")
		)
		(fp_line
			(start -1.7018 1.0414)
			(end -1.7018 2.9718)
			(stroke
				(width 0.635)
				(type default)
			)
			(layer "F.SilkS")
		)
		(fp_poly
			(pts
				(xy -1.1938 -1.016) (xy 1.0922 -1.016) (xy 1.0922 1.016) (xy -1.1938 1.016)
			)
			(stroke
				(width 0)
				(type default)
			)
			(fill yes)
			(layer "F.SilkS")
		)
		(fp_rect
			(start -2.0066 3.3401)
			(end 2.0066 -3.3401)
			(stroke
				(width 0)
				(type default)
			)
			(fill no)
			(layer "F.CrtYd")
		)
		(fp_poly
			(pts
				(xy -2.0066 -3.3401) (xy 2.0066 -3.3401) (xy 2.0066 3.3401) (xy -2.0066 3.3401)
			)
			(stroke
				(width 0)
				(type default)
			)
			(fill no)
			(layer "F.Fab")
		)
		(pad "1" smd rect
			(at -0.97536 2.0701 90)
			(size 0.4064 1.524)
			(layers "F.Cu" "F.Mask" "F.Paste")
			(net "I2C7_BUFF_EN")
		)
		(pad "2" smd rect
			(at -0.32512 2.0701 90)
			(size 0.4064 1.524)
			(layers "F.Cu" "F.Mask" "F.Paste")
			(net "BMC_I2C7_B_DBP_SCL_R")
		)
		(pad "3" smd rect
			(at 0.32512 2.0701 90)
			(size 0.4064 1.524)
			(layers "F.Cu" "F.Mask" "F.Paste")
			(net "BUF_I2C7_B_DBP_SCL_R")
		)
		(pad "4" smd rect
			(at 0.97536 2.0701 90)
			(size 0.4064 1.524)
			(layers "F.Cu" "F.Mask" "F.Paste")
			(net "GND")
		)
		(pad "5" smd rect
			(at 0.97536 -2.0701 90)
			(size 0.4064 1.524)
			(layers "F.Cu" "F.Mask" "F.Paste")
			(net "I2C7_BUF_READY")
		)
		(pad "6" smd rect
			(at 0.32512 -2.0701 90)
			(size 0.4064 1.524)
			(layers "F.Cu" "F.Mask" "F.Paste")
			(net "BUF_I2C7_B_DPB_SDA_R")
		)
		(pad "7" smd rect
			(at -0.32512 -2.0701 90)
			(size 0.4064 1.524)
			(layers "F.Cu" "F.Mask" "F.Paste")
			(net "BMC_I2C7_B_DPB_SDA_R")
		)
		(pad "8" smd rect
			(at -0.97536 -2.0701 90)
			(size 0.4064 1.524)
			(layers "F.Cu" "F.Mask" "F.Paste")
			(net "P3V3_STBY")
		)
	)
	(footprint ""
		(layer "F.Cu")
		(at 75.180952 -148.12391 90)
		(property "Reference" "R198"
			(at 0 0 90)
			(layer "F.SilkS")
			(hide yes)
			(effects
				(font
					(size 1.27 1.27)
				)
			)
		)
		(property "Value" "8K2R2J-3-GP"
			(at 0.064008 -3.993896 90)
			(unlocked yes)
			(layer "F.Fab")
			(hide yes)
			(effects
				(font
					(size 1.016 1.016)
					(thickness 0.1524)
				)
			)
		)
		(property "Device Type" "R402H16"
			(at 0.064008 -5.517896 90)
			(unlocked yes)
			(layer "F.Fab")
			(hide yes)
			(effects
				(font
					(size 1.016 1.016)
					(thickness 0.1524)
				)
			)
		)
		(duplicate_pad_numbers_are_jumpers no)
		(fp_line
			(start 0.508 -0.9398)
			(end -0.508 -0.9398)
			(stroke
				(width 0.1524)
				(type default)
			)
			(layer "F.SilkS")
		)
		(fp_line
			(start -0.508 -0.9398)
			(end -0.508 0.9398)
			(stroke
				(width 0.1524)
				(type default)
			)
			(layer "F.SilkS")
		)
		(fp_rect
			(start -0.508 0.9398)
			(end 0.508 -0.9398)
			(stroke
				(width 0)
				(type default)
			)
			(fill no)
			(layer "F.CrtYd")
		)
		(fp_rect
			(start -0.508 0.9398)
			(end 0.508 -0.9398)
			(stroke
				(width 0)
				(type default)
			)
			(fill no)
			(layer "F.Fab")
		)
		(pad "1" smd custom
			(at 0 -0.4445 90)
			(size 0.1397 0.1397)
			(layers "F.Cu" "F.Mask" "F.Paste")
			(net "EEPROM_A1_R")
			(options
				(clearance outline)
				(anchor circle)
			)
			(primitives
				(gr_poly
					(pts
						(arc
							(start -0.1778 -0.2794)
							(mid -0.249642 -0.249642)
							(end -0.2794 -0.1778)
						)
						(arc
							(start -0.2794 0.1778)
							(mid -0.249642 0.249642)
							(end -0.1778 0.2794)
						)
						(arc
							(start 0.1778 0.2794)
							(mid 0.249642 0.249642)
							(end 0.2794 0.1778)
						)
						(arc
							(start 0.2794 -0.1778)
							(mid 0.249642 -0.249642)
							(end 0.1778 -0.2794)
						)
					)
					(width 0)
					(fill yes)
				)
			)
		)
		(pad "2" smd custom
			(at 0 0.4445 90)
			(size 0.1397 0.1397)
			(layers "F.Cu" "F.Mask" "F.Paste")
			(net "GND")
			(options
				(clearance outline)
				(anchor circle)
			)
			(primitives
				(gr_poly
					(pts
						(arc
							(start -0.1778 -0.2794)
							(mid -0.249642 -0.249642)
							(end -0.2794 -0.1778)
						)
						(arc
							(start -0.2794 0.1778)
							(mid -0.249642 0.249642)
							(end -0.1778 0.2794)
						)
						(arc
							(start 0.1778 0.2794)
							(mid 0.249642 0.249642)
							(end 0.2794 0.1778)
						)
						(arc
							(start 0.2794 -0.1778)
							(mid 0.249642 -0.249642)
							(end 0.1778 -0.2794)
						)
					)
					(width 0)
					(fill yes)
				)
			)
		)
	)
	(footprint ""
		(layer "F.Cu")
		(at 218.885008 -4.064)
		(property "Reference" "SC1116"
			(at 0 0 0)
			(layer "F.SilkS")
			(hide yes)
			(effects
				(font
					(size 1.27 1.27)
				)
			)
		)
		(property "Value" "SCD1U16V2KX-3GP"
			(at 1.1811 -2.7051 0)
			(unlocked yes)
			(layer "F.Fab")
			(hide yes)
			(effects
				(font
					(size 1.016 1.016)
					(thickness 0.1524)
				)
			)
		)
		(property "Device Type" "C402H22"
			(at 1.1811 -4.2291 0)
			(unlocked yes)
			(layer "F.Fab")
			(hide yes)
			(effects
				(font
					(size 1.016 1.016)
					(thickness 0.1524)
				)
			)
		)
		(duplicate_pad_numbers_are_jumpers no)
		(fp_rect
			(start -0.4318 0.9525)
			(end 0.4318 -0.9525)
			(stroke
				(width 0)
				(type default)
			)
			(fill no)
			(layer "F.CrtYd")
		)
		(fp_rect
			(start -0.4318 0.9525)
			(end 0.4318 -0.9525)
			(stroke
				(width 0)
				(type default)
			)
			(fill no)
			(layer "F.Fab")
		)
		(pad "1" smd custom
			(at 0 -0.4445)
			(size 0.1524 0.1524)
			(layers "F.Cu" "F.Mask" "F.Paste")
			(net "P3V3_STBY")
			(options
				(clearance outline)
				(anchor circle)
			)
			(primitives
				(gr_poly
					(pts
						(arc
							(start 0.3048 -0.2032)
							(mid 0.275042 -0.275042)
							(end 0.2032 -0.3048)
						)
						(arc
							(start -0.2032 -0.3048)
							(mid -0.275042 -0.275042)
							(end -0.3048 -0.2032)
						)
						(arc
							(start -0.3048 0.2032)
							(mid -0.275042 0.275042)
							(end -0.2032 0.3048)
						)
						(arc
							(start 0.2032 0.3048)
							(mid 0.275042 0.275042)
							(end 0.3048 0.2032)
						)
					)
					(width 0)
					(fill yes)
				)
			)
		)
		(pad "2" smd custom
			(at 0 0.4445)
			(size 0.1524 0.1524)
			(layers "F.Cu" "F.Mask" "F.Paste")
			(net "GND")
			(options
				(clearance outline)
				(anchor circle)
			)
			(primitives
				(gr_poly
					(pts
						(arc
							(start 0.3048 -0.2032)
							(mid 0.275042 -0.275042)
							(end 0.2032 -0.3048)
						)
						(arc
							(start -0.2032 -0.3048)
							(mid -0.275042 -0.275042)
							(end -0.3048 -0.2032)
						)
						(arc
							(start -0.3048 0.2032)
							(mid -0.275042 0.275042)
							(end -0.2032 0.3048)
						)
						(arc
							(start 0.2032 0.3048)
							(mid 0.275042 0.275042)
							(end 0.3048 0.2032)
						)
					)
					(width 0)
					(fill yes)
				)
			)
		)
	)
)
